(kicad_pcb
	(version 20260206)
	(generator "pcbnew")
	(generator_version "10.0")
	(general
		(thickness 1.6)
		(legacy_teardrops no)
	)
	(paper "A4")
	(title_block
		(title "01162023_DA0F0TEBIF0_F0T_Expander_BD_F_brd_V02_OCP.brd")
		(comment 1 "Grand Teton / footprints 598-604 of 9728")
	)
	(layers
		(0 "F.Cu" signal "TOP")
		(4 "In1.Cu" signal "GND")
		(6 "In2.Cu" signal "VCC")
		(8 "In3.Cu" signal "VCC1")
		(10 "In4.Cu" signal "GND1")
		(12 "In5.Cu" signal "IN1")
		(14 "In6.Cu" signal "GND2")
		(16 "In7.Cu" signal "IN2")
		(18 "In8.Cu" signal "GND3")
		(20 "In9.Cu" signal "IN3")
		(22 "In10.Cu" signal "GND4")
		(24 "In11.Cu" signal "IN4")
		(26 "In12.Cu" signal "GND5")
		(28 "In13.Cu" signal "IN5")
		(30 "In14.Cu" signal "GND6")
		(32 "In15.Cu" signal "IN6")
		(34 "In16.Cu" signal "GND7")
		(2 "B.Cu" signal "BOTTOM")
		(9 "F.Adhes" user "F.Adhesive")
		(11 "B.Adhes" user "B.Adhesive")
		(13 "F.Paste" user "Package Geometry/Pastemask Top")
		(15 "B.Paste" user "Package Geometry/Pastemask Bottom")
		(5 "F.SilkS" user "Ref Des/Silkscreen Top")
		(7 "B.SilkS" user "Ref Des/Silkscreen Bottom")
		(1 "F.Mask" user "Board Geometry/Soldermask Top")
		(3 "B.Mask" user "Board Geometry/Soldermask Bottom")
		(17 "Dwgs.User" user "User.Drawings")
		(19 "Cmts.User" user "User.Comments")
		(21 "Eco1.User" user "User.Eco1")
		(23 "Eco2.User" user "User.Eco2")
		(25 "Edge.Cuts" user "Board Geometry/Outline")
		(27 "Margin" user)
		(31 "F.CrtYd" user "Package Geometry/Place Bound Top")
		(29 "B.CrtYd" user "Package Geometry/Place Bound Bottom")
		(35 "F.Fab" user "Ref Des/Assembly Top")
		(33 "B.Fab" user "Ref Des/Assembly Bottom")
	)
	(footprint ""
		(layer "F.Cu")
		(at 217.235786 -223.382586 180)
		(property "Reference" "R1485"
			(at 0 0 180)
			(layer "F.SilkS")
			(hide yes)
			(effects
				(font
					(size 1.27 1.27)
				)
			)
		)
		(property "Value" ""
			(at 0 0 180)
			(layer "F.Fab")
			(effects
				(font
					(size 1.27 1.27)
				)
			)
		)
		(duplicate_pad_numbers_are_jumpers no)
		(fp_line
			(start 0.7874 0.4064)
			(end -0.7874 0.4064)
			(stroke
				(width 0.1524)
				(type default)
			)
			(layer "F.SilkS")
		)
		(fp_line
			(start 0.7874 -0.4064)
			(end 0.7874 0.4064)
			(stroke
				(width 0.1524)
				(type default)
			)
			(layer "F.SilkS")
		)
		(fp_line
			(start -0.7874 0.4064)
			(end -0.7874 -0.4064)
			(stroke
				(width 0.1524)
				(type default)
			)
			(layer "F.SilkS")
		)
		(fp_line
			(start -0.7874 -0.4064)
			(end 0.7874 -0.4064)
			(stroke
				(width 0.1524)
				(type default)
			)
			(layer "F.SilkS")
		)
		(fp_line
			(start 0.67945 0.3048)
			(end 0.120396 0.3048)
			(stroke
				(width 0.1)
				(type default)
			)
			(layer "F.Fab")
		)
		(fp_line
			(start 0.67945 -0.3048)
			(end 0.67945 0.3048)
			(stroke
				(width 0.1)
				(type default)
			)
			(layer "F.Fab")
		)
		(fp_line
			(start 0.12065 -0.2794)
			(end 0.12065 -0.3048)
			(stroke
				(width 0.1)
				(type default)
			)
			(layer "F.Fab")
		)
		(fp_line
			(start 0.12065 -0.3048)
			(end 0.67945 -0.3048)
			(stroke
				(width 0.1)
				(type default)
			)
			(layer "F.Fab")
		)
		(fp_line
			(start 0.120396 0.3048)
			(end 0.120396 0.2794)
			(stroke
				(width 0.1)
				(type default)
			)
			(layer "F.Fab")
		)
		(fp_line
			(start 0.120396 0.2794)
			(end -0.12065 0.2794)
			(stroke
				(width 0.1)
				(type default)
			)
			(layer "F.Fab")
		)
		(fp_line
			(start -0.12065 0.3048)
			(end -0.67945 0.3048)
			(stroke
				(width 0.1)
				(type default)
			)
			(layer "F.Fab")
		)
		(fp_line
			(start -0.12065 0.2794)
			(end -0.12065 0.3048)
			(stroke
				(width 0.1)
				(type default)
			)
			(layer "F.Fab")
		)
		(fp_line
			(start -0.12065 -0.2794)
			(end 0.12065 -0.2794)
			(stroke
				(width 0.1)
				(type default)
			)
			(layer "F.Fab")
		)
		(fp_line
			(start -0.12065 -0.305054)
			(end -0.12065 -0.2794)
			(stroke
				(width 0.1)
				(type default)
			)
			(layer "F.Fab")
		)
		(fp_line
			(start -0.67945 0.3048)
			(end -0.67945 -0.305054)
			(stroke
				(width 0.1)
				(type default)
			)
			(layer "F.Fab")
		)
		(fp_line
			(start -0.67945 -0.305054)
			(end -0.12065 -0.305054)
			(stroke
				(width 0.1)
				(type default)
			)
			(layer "F.Fab")
		)
		(pad "1" smd circle
			(at -0.40005 0 180)
			(size 0 0)
			(layers "F.Cu" "F.Mask" "F.Paste")
			(net "I3C_MB_SDA")
		)
		(pad "2" smd circle
			(at 0.40005 0 180)
			(size 0 0)
			(layers "F.Cu" "F.Mask" "F.Paste")
			(net "SMB_MB_I3C_ISO_SDA")
		)
	)
	(footprint ""
		(layer "F.Cu")
		(at 205.112366 -300.64202 -90)
		(property "Reference" "R3931"
			(at 0 0 270)
			(layer "F.SilkS")
			(hide yes)
			(effects
				(font
					(size 1.27 1.27)
				)
			)
		)
		(property "Value" ""
			(at 0 0 270)
			(layer "F.Fab")
			(effects
				(font
					(size 1.27 1.27)
				)
			)
		)
		(duplicate_pad_numbers_are_jumpers no)
		(fp_line
			(start -0.7874 0.4064)
			(end -0.7874 -0.4064)
			(stroke
				(width 0.1524)
				(type default)
			)
			(layer "F.SilkS")
		)
		(fp_line
			(start 0.7874 0.4064)
			(end -0.7874 0.4064)
			(stroke
				(width 0.1524)
				(type default)
			)
			(layer "F.SilkS")
		)
		(fp_line
			(start -0.7874 -0.4064)
			(end 0.7874 -0.4064)
			(stroke
				(width 0.1524)
				(type default)
			)
			(layer "F.SilkS")
		)
		(fp_line
			(start 0.7874 -0.4064)
			(end 0.7874 0.4064)
			(stroke
				(width 0.1524)
				(type default)
			)
			(layer "F.SilkS")
		)
		(fp_line
			(start -0.67945 0.3048)
			(end -0.67945 -0.305054)
			(stroke
				(width 0.1)
				(type default)
			)
			(layer "F.Fab")
		)
		(fp_line
			(start -0.12065 0.3048)
			(end -0.67945 0.3048)
			(stroke
				(width 0.1)
				(type default)
			)
			(layer "F.Fab")
		)
		(fp_line
			(start 0.120396 0.3048)
			(end 0.120396 0.2794)
			(stroke
				(width 0.1)
				(type default)
			)
			(layer "F.Fab")
		)
		(fp_line
			(start 0.67945 0.3048)
			(end 0.120396 0.3048)
			(stroke
				(width 0.1)
				(type default)
			)
			(layer "F.Fab")
		)
		(fp_line
			(start -0.12065 0.2794)
			(end -0.12065 0.3048)
			(stroke
				(width 0.1)
				(type default)
			)
			(layer "F.Fab")
		)
		(fp_line
			(start 0.120396 0.2794)
			(end -0.12065 0.2794)
			(stroke
				(width 0.1)
				(type default)
			)
			(layer "F.Fab")
		)
		(fp_line
			(start -0.12065 -0.2794)
			(end 0.12065 -0.2794)
			(stroke
				(width 0.1)
				(type default)
			)
			(layer "F.Fab")
		)
		(fp_line
			(start 0.12065 -0.2794)
			(end 0.12065 -0.3048)
			(stroke
				(width 0.1)
				(type default)
			)
			(layer "F.Fab")
		)
		(fp_line
			(start 0.12065 -0.3048)
			(end 0.67945 -0.3048)
			(stroke
				(width 0.1)
				(type default)
			)
			(layer "F.Fab")
		)
		(fp_line
			(start 0.67945 -0.3048)
			(end 0.67945 0.3048)
			(stroke
				(width 0.1)
				(type default)
			)
			(layer "F.Fab")
		)
		(fp_line
			(start -0.67945 -0.305054)
			(end -0.12065 -0.305054)
			(stroke
				(width 0.1)
				(type default)
			)
			(layer "F.Fab")
		)
		(fp_line
			(start -0.12065 -0.305054)
			(end -0.12065 -0.2794)
			(stroke
				(width 0.1)
				(type default)
			)
			(layer "F.Fab")
		)
		(pad "1" smd circle
			(at -0.40005 0 270)
			(size 0 0)
			(layers "F.Cu" "F.Mask" "F.Paste")
			(net "I2C0_PEX1_SHPC_SDA")
		)
		(pad "2" smd circle
			(at 0.40005 0 270)
			(size 0 0)
			(layers "F.Cu" "F.Mask" "F.Paste")
			(net "I2C_PEX1_HOST_SDA")
		)
	)
	(footprint ""
		(layer "F.Cu")
		(at 224.851976 -366.994186)
		(property "Reference" "PR29"
			(at 0 0 0)
			(layer "F.SilkS")
			(hide yes)
			(effects
				(font
					(size 1.27 1.27)
				)
			)
		)
		(property "Value" ""
			(at 0 0 0)
			(layer "F.Fab")
			(effects
				(font
					(size 1.27 1.27)
				)
			)
		)
		(duplicate_pad_numbers_are_jumpers no)
		(fp_line
			(start -0.7874 -0.4064)
			(end 0.7874 -0.4064)
			(stroke
				(width 0.1524)
				(type default)
			)
			(layer "F.SilkS")
		)
		(fp_line
			(start -0.7874 0.4064)
			(end -0.7874 -0.4064)
			(stroke
				(width 0.1524)
				(type default)
			)
			(layer "F.SilkS")
		)
		(fp_line
			(start 0.7874 -0.4064)
			(end 0.7874 0.4064)
			(stroke
				(width 0.1524)
				(type default)
			)
			(layer "F.SilkS")
		)
		(fp_line
			(start 0.7874 0.4064)
			(end -0.7874 0.4064)
			(stroke
				(width 0.1524)
				(type default)
			)
			(layer "F.SilkS")
		)
		(fp_line
			(start -0.67945 -0.305054)
			(end -0.12065 -0.305054)
			(stroke
				(width 0.1)
				(type default)
			)
			(layer "F.Fab")
		)
		(fp_line
			(start -0.67945 0.3048)
			(end -0.67945 -0.305054)
			(stroke
				(width 0.1)
				(type default)
			)
			(layer "F.Fab")
		)
		(fp_line
			(start -0.12065 -0.305054)
			(end -0.12065 -0.2794)
			(stroke
				(width 0.1)
				(type default)
			)
			(layer "F.Fab")
		)
		(fp_line
			(start -0.12065 -0.2794)
			(end 0.12065 -0.2794)
			(stroke
				(width 0.1)
				(type default)
			)
			(layer "F.Fab")
		)
		(fp_line
			(start -0.12065 0.2794)
			(end -0.12065 0.3048)
			(stroke
				(width 0.1)
				(type default)
			)
			(layer "F.Fab")
		)
		(fp_line
			(start -0.12065 0.3048)
			(end -0.67945 0.3048)
			(stroke
				(width 0.1)
				(type default)
			)
			(layer "F.Fab")
		)
		(fp_line
			(start 0.120396 0.2794)
			(end -0.12065 0.2794)
			(stroke
				(width 0.1)
				(type default)
			)
			(layer "F.Fab")
		)
		(fp_line
			(start 0.120396 0.3048)
			(end 0.120396 0.2794)
			(stroke
				(width 0.1)
				(type default)
			)
			(layer "F.Fab")
		)
		(fp_line
			(start 0.12065 -0.3048)
			(end 0.67945 -0.3048)
			(stroke
				(width 0.1)
				(type default)
			)
			(layer "F.Fab")
		)
		(fp_line
			(start 0.12065 -0.2794)
			(end 0.12065 -0.3048)
			(stroke
				(width 0.1)
				(type default)
			)
			(layer "F.Fab")
		)
		(fp_line
			(start 0.67945 -0.3048)
			(end 0.67945 0.3048)
			(stroke
				(width 0.1)
				(type default)
			)
			(layer "F.Fab")
		)
		(fp_line
			(start 0.67945 0.3048)
			(end 0.120396 0.3048)
			(stroke
				(width 0.1)
				(type default)
			)
			(layer "F.Fab")
		)
		(pad "1" smd circle
			(at -0.40005 0)
			(size 0 0)
			(layers "F.Cu" "F.Mask" "F.Paste")
			(net "HSC_D_OC_1")
		)
		(pad "2" smd circle
			(at 0.40005 0)
			(size 0 0)
			(layers "F.Cu" "F.Mask" "F.Paste")
			(net "HSC_D_OC")
		)
	)
	(footprint ""
		(layer "F.Cu")
		(at 397.956532 -20.467574 180)
		(property "Reference" "R1720"
			(at 0 0 180)
			(layer "F.SilkS")
			(hide yes)
			(effects
				(font
					(size 1.27 1.27)
				)
			)
		)
		(property "Value" ""
			(at 0 0 180)
			(layer "F.Fab")
			(effects
				(font
					(size 1.27 1.27)
				)
			)
		)
		(duplicate_pad_numbers_are_jumpers no)
		(fp_line
			(start 0.7874 0.4064)
			(end -0.7874 0.4064)
			(stroke
				(width 0.1524)
				(type default)
			)
			(layer "F.SilkS")
		)
		(fp_line
			(start 0.7874 -0.4064)
			(end 0.7874 0.4064)
			(stroke
				(width 0.1524)
				(type default)
			)
			(layer "F.SilkS")
		)
		(fp_line
			(start -0.7874 0.4064)
			(end -0.7874 -0.4064)
			(stroke
				(width 0.1524)
				(type default)
			)
			(layer "F.SilkS")
		)
		(fp_line
			(start -0.7874 -0.4064)
			(end 0.7874 -0.4064)
			(stroke
				(width 0.1524)
				(type default)
			)
			(layer "F.SilkS")
		)
		(fp_line
			(start 0.67945 0.3048)
			(end 0.120396 0.3048)
			(stroke
				(width 0.1)
				(type default)
			)
			(layer "F.Fab")
		)
		(fp_line
			(start 0.67945 -0.3048)
			(end 0.67945 0.3048)
			(stroke
				(width 0.1)
				(type default)
			)
			(layer "F.Fab")
		)
		(fp_line
			(start 0.12065 -0.2794)
			(end 0.12065 -0.3048)
			(stroke
				(width 0.1)
				(type default)
			)
			(layer "F.Fab")
		)
		(fp_line
			(start 0.12065 -0.3048)
			(end 0.67945 -0.3048)
			(stroke
				(width 0.1)
				(type default)
			)
			(layer "F.Fab")
		)
		(fp_line
			(start 0.120396 0.3048)
			(end 0.120396 0.2794)
			(stroke
				(width 0.1)
				(type default)
			)
			(layer "F.Fab")
		)
		(fp_line
			(start 0.120396 0.2794)
			(end -0.12065 0.2794)
			(stroke
				(width 0.1)
				(type default)
			)
			(layer "F.Fab")
		)
		(fp_line
			(start -0.12065 0.3048)
			(end -0.67945 0.3048)
			(stroke
				(width 0.1)
				(type default)
			)
			(layer "F.Fab")
		)
		(fp_line
			(start -0.12065 0.2794)
			(end -0.12065 0.3048)
			(stroke
				(width 0.1)
				(type default)
			)
			(layer "F.Fab")
		)
		(fp_line
			(start -0.12065 -0.2794)
			(end 0.12065 -0.2794)
			(stroke
				(width 0.1)
				(type default)
			)
			(layer "F.Fab")
		)
		(fp_line
			(start -0.12065 -0.305054)
			(end -0.12065 -0.2794)
			(stroke
				(width 0.1)
				(type default)
			)
			(layer "F.Fab")
		)
		(fp_line
			(start -0.67945 0.3048)
			(end -0.67945 -0.305054)
			(stroke
				(width 0.1)
				(type default)
			)
			(layer "F.Fab")
		)
		(fp_line
			(start -0.67945 -0.305054)
			(end -0.12065 -0.305054)
			(stroke
				(width 0.1)
				(type default)
			)
			(layer "F.Fab")
		)
		(pad "1" smd circle
			(at -0.40005 0 180)
			(size 0 0)
			(layers "F.Cu" "F.Mask" "F.Paste")
			(net "P3V3_SSD13")
		)
		(pad "2" smd circle
			(at 0.40005 0 180)
			(size 0 0)
			(layers "F.Cu" "F.Mask" "F.Paste")
			(net "SMB_ISO_SSD13_SDA")
		)
	)
	(footprint ""
		(layer "F.Cu")
		(at 234.13466 -207.02016 -90)
		(property "Reference" "R5712"
			(at 0 0 270)
			(layer "F.SilkS")
			(hide yes)
			(effects
				(font
					(size 1.27 1.27)
				)
			)
		)
		(property "Value" ""
			(at 0 0 270)
			(layer "F.Fab")
			(effects
				(font
					(size 1.27 1.27)
				)
			)
		)
		(duplicate_pad_numbers_are_jumpers no)
		(fp_line
			(start -0.7874 0.4064)
			(end -0.7874 -0.4064)
			(stroke
				(width 0.1524)
				(type default)
			)
			(layer "F.SilkS")
		)
		(fp_line
			(start 0.7874 0.4064)
			(end -0.7874 0.4064)
			(stroke
				(width 0.1524)
				(type default)
			)
			(layer "F.SilkS")
		)
		(fp_line
			(start -0.7874 -0.4064)
			(end 0.7874 -0.4064)
			(stroke
				(width 0.1524)
				(type default)
			)
			(layer "F.SilkS")
		)
		(fp_line
			(start 0.7874 -0.4064)
			(end 0.7874 0.4064)
			(stroke
				(width 0.1524)
				(type default)
			)
			(layer "F.SilkS")
		)
		(fp_line
			(start -0.67945 0.3048)
			(end -0.67945 -0.305054)
			(stroke
				(width 0.1)
				(type default)
			)
			(layer "F.Fab")
		)
		(fp_line
			(start -0.12065 0.3048)
			(end -0.67945 0.3048)
			(stroke
				(width 0.1)
				(type default)
			)
			(layer "F.Fab")
		)
		(fp_line
			(start 0.120396 0.3048)
			(end 0.120396 0.2794)
			(stroke
				(width 0.1)
				(type default)
			)
			(layer "F.Fab")
		)
		(fp_line
			(start 0.67945 0.3048)
			(end 0.120396 0.3048)
			(stroke
				(width 0.1)
				(type default)
			)
			(layer "F.Fab")
		)
		(fp_line
			(start -0.12065 0.2794)
			(end -0.12065 0.3048)
			(stroke
				(width 0.1)
				(type default)
			)
			(layer "F.Fab")
		)
		(fp_line
			(start 0.120396 0.2794)
			(end -0.12065 0.2794)
			(stroke
				(width 0.1)
				(type default)
			)
			(layer "F.Fab")
		)
		(fp_line
			(start -0.12065 -0.2794)
			(end 0.12065 -0.2794)
			(stroke
				(width 0.1)
				(type default)
			)
			(layer "F.Fab")
		)
		(fp_line
			(start 0.12065 -0.2794)
			(end 0.12065 -0.3048)
			(stroke
				(width 0.1)
				(type default)
			)
			(layer "F.Fab")
		)
		(fp_line
			(start 0.12065 -0.3048)
			(end 0.67945 -0.3048)
			(stroke
				(width 0.1)
				(type default)
			)
			(layer "F.Fab")
		)
		(fp_line
			(start 0.67945 -0.3048)
			(end 0.67945 0.3048)
			(stroke
				(width 0.1)
				(type default)
			)
			(layer "F.Fab")
		)
		(fp_line
			(start -0.67945 -0.305054)
			(end -0.12065 -0.305054)
			(stroke
				(width 0.1)
				(type default)
			)
			(layer "F.Fab")
		)
		(fp_line
			(start -0.12065 -0.305054)
			(end -0.12065 -0.2794)
			(stroke
				(width 0.1)
				(type default)
			)
			(layer "F.Fab")
		)
		(pad "1" smd circle
			(at -0.40005 0 270)
			(size 0 0)
			(layers "F.Cu" "F.Mask" "F.Paste")
			(net "PD_BIC_ENTEST")
		)
		(pad "2" smd circle
			(at 0.40005 0 270)
			(size 0 0)
			(layers "F.Cu" "F.Mask" "F.Paste")
			(net "GND")
		)
	)
	(footprint ""
		(layer "F.Cu")
		(at 461.924908 -308.692296)
		(property "Reference" "PJ15"
			(at 0 0 0)
			(layer "F.SilkS")
			(hide yes)
			(effects
				(font
					(size 1.27 1.27)
				)
			)
		)
		(property "Value" ""
			(at 0 0 0)
			(layer "F.Fab")
			(effects
				(font
					(size 1.27 1.27)
				)
			)
		)
		(duplicate_pad_numbers_are_jumpers no)
		(pad "1" smd circle
			(at -0.40005 0 90)
			(size 0 0)
			(layers "F.Cu" "F.Mask" "F.Paste")
			(net "SH_P1V25_PEX3_FB_P")
		)
		(pad "2" smd rect
			(at 0.40005 0 180)
			(size 0.4572 0.508)
			(layers "F.Cu" "F.Mask" "F.Paste")
			(net "P1V25_PEX3")
		)
		(zone
			(layer "F.Cu")
			(hatch none 0.5)
			(connect_pads
				(clearance 0)
			)
			(min_thickness 0.25)
			(keepout
				(tracks allowed)
				(vias not_allowed)
				(pads allowed)
				(copperpour not_allowed)
				(footprints allowed)
			)
			(placement
				(enabled no)
				(sheetname "")
			)
			(fill
				(thermal_gap 0.5)
				(thermal_bridge_width 0.5)
				(island_removal_mode 0)
			)
			(polygon
				(pts
					(xy 461.239108 -308.387496) (xy 462.610708 -308.387496) (xy 462.610708 -308.997096) (xy 461.239108 -308.997096)
				)
			)
		)
	)
	(footprint ""
		(layer "F.Cu")
		(at 257.170682 -348.674436 180)
		(property "Reference" "R6650"
			(at 0 0 180)
			(layer "F.SilkS")
			(hide yes)
			(effects
				(font
					(size 1.27 1.27)
				)
			)
		)
		(property "Value" ""
			(at 0 0 180)
			(layer "F.Fab")
			(effects
				(font
					(size 1.27 1.27)
				)
			)
		)
		(duplicate_pad_numbers_are_jumpers no)
		(fp_line
			(start 0.7874 0.4064)
			(end -0.7874 0.4064)
			(stroke
				(width 0.1524)
				(type default)
			)
			(layer "F.SilkS")
		)
		(fp_line
			(start 0.7874 -0.4064)
			(end 0.7874 0.4064)
			(stroke
				(width 0.1524)
				(type default)
			)
			(layer "F.SilkS")
		)
		(fp_line
			(start -0.7874 0.4064)
			(end -0.7874 -0.4064)
			(stroke
				(width 0.1524)
				(type default)
			)
			(layer "F.SilkS")
		)
		(fp_line
			(start -0.7874 -0.4064)
			(end 0.7874 -0.4064)
			(stroke
				(width 0.1524)
				(type default)
			)
			(layer "F.SilkS")
		)
		(fp_line
			(start 0.67945 0.3048)
			(end 0.120396 0.3048)
			(stroke
				(width 0.1)
				(type default)
			)
			(layer "F.Fab")
		)
		(fp_line
			(start 0.67945 -0.3048)
			(end 0.67945 0.3048)
			(stroke
				(width 0.1)
				(type default)
			)
			(layer "F.Fab")
		)
		(fp_line
			(start 0.12065 -0.2794)
			(end 0.12065 -0.3048)
			(stroke
				(width 0.1)
				(type default)
			)
			(layer "F.Fab")
		)
		(fp_line
			(start 0.12065 -0.3048)
			(end 0.67945 -0.3048)
			(stroke
				(width 0.1)
				(type default)
			)
			(layer "F.Fab")
		)
		(fp_line
			(start 0.120396 0.3048)
			(end 0.120396 0.2794)
			(stroke
				(width 0.1)
				(type default)
			)
			(layer "F.Fab")
		)
		(fp_line
			(start 0.120396 0.2794)
			(end -0.12065 0.2794)
			(stroke
				(width 0.1)
				(type default)
			)
			(layer "F.Fab")
		)
		(fp_line
			(start -0.12065 0.3048)
			(end -0.67945 0.3048)
			(stroke
				(width 0.1)
				(type default)
			)
			(layer "F.Fab")
		)
		(fp_line
			(start -0.12065 0.2794)
			(end -0.12065 0.3048)
			(stroke
				(width 0.1)
				(type default)
			)
			(layer "F.Fab")
		)
		(fp_line
			(start -0.12065 -0.2794)
			(end 0.12065 -0.2794)
			(stroke
				(width 0.1)
				(type default)
			)
			(layer "F.Fab")
		)
		(fp_line
			(start -0.12065 -0.305054)
			(end -0.12065 -0.2794)
			(stroke
				(width 0.1)
				(type default)
			)
			(layer "F.Fab")
		)
		(fp_line
			(start -0.67945 0.3048)
			(end -0.67945 -0.305054)
			(stroke
				(width 0.1)
				(type default)
			)
			(layer "F.Fab")
		)
		(fp_line
			(start -0.67945 -0.305054)
			(end -0.12065 -0.305054)
			(stroke
				(width 0.1)
				(type default)
			)
			(layer "F.Fab")
		)
		(pad "1" smd circle
			(at -0.40005 0 180)
			(size 0 0)
			(layers "F.Cu" "F.Mask" "F.Paste")
			(net "A_HSC_LOW")
		)
		(pad "2" smd circle
			(at 0.40005 0 180)
			(size 0 0)
			(layers "F.Cu" "F.Mask" "F.Paste")
			(net "GND")
		)
	)
)
